(kicad_pcb
	(version 20240108)
	(generator "pcbnew")
	(generator_version "8.0")
	(general
		(thickness 1.62)
		(legacy_teardrops no)
	)
	(paper "A4")
	(title_block
		(title "Jetson Orin Baseboard")
		(date "2025-03-12")
		(rev "1.3.4")
		(company "Antmicro Ltd")
		(comment 1 "www.antmicro.com")
		(comment 9 "footprints 217-221 of 677")
	)
	(layers
		(0 "F.Cu" signal)
		(1 "In1.Cu" signal)
		(2 "In2.Cu" signal)
		(3 "In3.Cu" signal)
		(4 "In4.Cu" jumper)
		(5 "In5.Cu" signal)
		(6 "In6.Cu" signal)
		(31 "B.Cu" signal)
		(32 "B.Adhes" user "B.Adhesive")
		(33 "F.Adhes" user "F.Adhesive")
		(34 "B.Paste" user)
		(35 "F.Paste" user)
		(36 "B.SilkS" user "B.Silkscreen")
		(37 "F.SilkS" user "F.Silkscreen")
		(38 "B.Mask" user)
		(39 "F.Mask" user)
		(40 "Dwgs.User" user "User.Drawings")
		(41 "Cmts.User" user "User.Comments")
		(42 "Eco1.User" user "User.Eco1")
		(43 "Eco2.User" user "User.Eco2")
		(44 "Edge.Cuts" user)
		(45 "Margin" user)
		(46 "B.CrtYd" user "B.Courtyard")
		(47 "F.CrtYd" user "F.Courtyard")
		(48 "B.Fab" user)
		(49 "F.Fab" user)
	)
	(footprint "antmicro-footprints:R_0402_1005Metric"
		(layer "F.Cu")
		(at 88.95 88.7 -90)
		(descr "Resistor SMD 0402")
		(tags "resistor SMD 0402")
		(property "Reference" "R278"
			(at -0.92 -0.3 -90)
			(layer "F.SilkS")
			(effects
				(font
					(size 0.7 0.7)
					(thickness 0.15)
				)
				(justify left bottom)
			)
		)
		(property "Value" "R_0R_0402"
			(at 0 1.4 -90)
			(layer "F.Fab")
			(effects
				(font
					(size 0.7 0.7)
					(thickness 0.15)
				)
				(justify left bottom)
			)
		)
		(property "Footprint" "antmicro-footprints:R_0402_1005Metric"
			(at 0 0 -90)
			(layer "F.Fab")
			(hide yes)
			(effects
				(font
					(size 1.27 1.27)
					(thickness 0.15)
				)
			)
		)
		(property "Datasheet" "https://industrial.panasonic.com/cdbs/www-data/pdf/RDA0000/AOA0000C301.pdf"
			(at 0 0 -90)
			(layer "F.Fab")
			(hide yes)
			(effects
				(font
					(size 1.27 1.27)
					(thickness 0.15)
				)
			)
		)
		(property "Author" "Antmicro"
			(at 0.25 177.65 0)
			(layer "F.Fab")
			(hide yes)
			(effects
				(font
					(size 1 1)
					(thickness 0.15)
				)
			)
		)
		(property "Current" "1A"
			(at 0.25 177.65 0)
			(layer "F.Fab")
			(hide yes)
			(effects
				(font
					(size 1 1)
					(thickness 0.15)
				)
			)
		)
		(property "License" "Apache-2.0"
			(at 0.25 177.65 0)
			(layer "F.Fab")
			(hide yes)
			(effects
				(font
					(size 1 1)
					(thickness 0.15)
				)
			)
		)
		(property "MPN" "ERJ2GE0R00X"
			(at 0.25 177.65 0)
			(layer "F.Fab")
			(hide yes)
			(effects
				(font
					(size 1 1)
					(thickness 0.15)
				)
			)
		)
		(property "Manufacturer" "Panasonic"
			(at 0.25 177.65 0)
			(layer "F.Fab")
			(hide yes)
			(effects
				(font
					(size 1 1)
					(thickness 0.15)
				)
			)
		)
		(property "Tolerance" ""
			(at 0.25 177.65 0)
			(layer "F.Fab")
			(hide yes)
			(effects
				(font
					(size 1 1)
					(thickness 0.15)
				)
			)
		)
		(property "Val" "0R"
			(at 0.25 177.65 0)
			(layer "F.Fab")
			(hide yes)
			(effects
				(font
					(size 1 1)
					(thickness 0.15)
				)
			)
		)
		(sheetname "HDMI")
		(sheetfile "hdmi.kicad_sch")
		(attr smd)
		(fp_rect
			(start -0.925 -0.47)
			(end 0.925 0.47)
			(stroke
				(width 0.05)
				(type default)
			)
			(fill none)
			(layer "F.CrtYd")
		)
		(fp_rect
			(start -0.5 -0.25)
			(end 0.5 0.25)
			(stroke
				(width 0.15)
				(type solid)
			)
			(fill none)
			(layer "F.Fab")
		)
		(fp_text user "${REFERENCE}"
			(at -0.95 3.168 -90)
			(layer "F.Fab")
			(hide yes)
			(effects
				(font
					(size 0.7 0.7)
					(thickness 0.15)
				)
				(justify left bottom)
			)
		)
		(fp_text user "Author: Antmicro"
			(at -0.95 4.169 -90)
			(layer "F.Fab")
			(hide yes)
			(effects
				(font
					(size 0.7 0.7)
					(thickness 0.15)
				)
				(justify left bottom)
			)
		)
		(fp_text user "License: Apache-2.0"
			(at -0.95 5.169 -90)
			(layer "F.Fab")
			(hide yes)
			(effects
				(font
					(size 0.7 0.7)
					(thickness 0.15)
				)
				(justify left bottom)
			)
		)
		(pad "1" smd roundrect
			(at -0.48 0 270)
			(size 0.59 0.64)
			(layers "F.Cu" "F.Paste" "F.Mask")
			(roundrect_rratio 0.25)
			(net 680 "/HDMI/DP_MUX_AUX_A-")
			(pintype "passive")
		)
		(pad "2" smd roundrect
			(at 0.48 0 270)
			(size 0.59 0.64)
			(layers "F.Cu" "F.Paste" "F.Mask")
			(roundrect_rratio 0.25)
			(net 701 "/HDMI/HDMI_SDA_3V3")
			(pintype "passive")
		)
	)
	(footprint "antmicro-footprints:XDFN-2_1x0.60mm"
		(layer "F.Cu")
		(at 135.1 89.841 -90)
		(property "Reference" "D44"
			(at 0.298 -0.402 180)
			(layer "F.SilkS")
			(effects
				(font
					(size 0.7 0.7)
					(thickness 0.15)
				)
				(justify left bottom)
			)
		)
		(property "Value" "TPD1E0B04_XDFN-2"
			(at 0 1.5 -90)
			(layer "F.Fab")
			(effects
				(font
					(size 0.7 0.7)
					(thickness 0.15)
				)
				(justify left bottom)
			)
		)
		(property "Footprint" "antmicro-footprints:XDFN-2_1x0.60mm"
			(at 0 0 -90)
			(layer "F.Fab")
			(hide yes)
			(effects
				(font
					(size 1.27 1.27)
					(thickness 0.15)
				)
			)
		)
		(property "Datasheet" "https://www.ti.com/general/docs/suppproductinfo.tsp?distId=26&gotoUrl=https://www.ti.com/lit/gpn/tpd1e0b04"
			(at 0 0 -90)
			(layer "F.Fab")
			(hide yes)
			(effects
				(font
					(size 1.27 1.27)
					(thickness 0.15)
				)
			)
		)
		(property "MPN" "TPD1E0B04DPYR"
			(at 45.259 224.941 0)
			(layer "F.Fab")
			(hide yes)
			(effects
				(font
					(size 1 1)
					(thickness 0.15)
				)
			)
		)
		(property "Manufacturer" "Texas Instruments"
			(at 45.259 224.941 0)
			(layer "F.Fab")
			(hide yes)
			(effects
				(font
					(size 1 1)
					(thickness 0.15)
				)
			)
		)
		(property "Author" "Antmicro"
			(at 45.259 224.941 0)
			(layer "F.Fab")
			(hide yes)
			(effects
				(font
					(size 1 1)
					(thickness 0.15)
				)
			)
		)
		(property "License" "Apache-2.0"
			(at 45.259 224.941 0)
			(layer "F.Fab")
			(hide yes)
			(effects
				(font
					(size 1 1)
					(thickness 0.15)
				)
			)
		)
		(sheetname "Peripherals")
		(sheetfile "peripherals.kicad_sch")
		(attr smd)
		(fp_rect
			(start -0.725 -0.475)
			(end 0.725 0.475)
			(stroke
				(width 0.05)
				(type solid)
			)
			(fill none)
			(layer "F.CrtYd")
		)
		(fp_rect
			(start -0.55 -0.35)
			(end 0.55 0.35)
			(stroke
				(width 0.15)
				(type solid)
			)
			(fill none)
			(layer "F.Fab")
		)
		(fp_text user "Author: Antmicro"
			(at -0.8 4.4 -90)
			(layer "F.Fab")
			(hide yes)
			(effects
				(font
					(size 0.7 0.7)
					(thickness 0.15)
				)
				(justify left bottom)
			)
		)
		(fp_text user "${REFERENCE}"
			(at -0.8 3.2 -90)
			(layer "F.Fab")
			(hide yes)
			(effects
				(font
					(size 0.7 0.7)
					(thickness 0.15)
				)
				(justify left bottom)
			)
		)
		(fp_text user "License: Apache-2.0"
			(at -0.8 5.6 -90)
			(layer "F.Fab")
			(hide yes)
			(effects
				(font
					(size 0.7 0.7)
					(thickness 0.15)
				)
				(justify left bottom)
			)
		)
		(pad "1" smd roundrect
			(at -0.351 0 270)
			(size 0.3 0.5)
			(layers "F.Cu" "F.Paste" "F.Mask")
			(roundrect_rratio 0.25)
			(net 166 "PCIE2_CLK_P")
			(pinfunction "C")
			(pintype "passive")
		)
		(pad "2" smd roundrect
			(at 0.349 0 270)
			(size 0.3 0.5)
			(layers "F.Cu" "F.Paste" "F.Mask")
			(roundrect_rratio 0.25)
			(net 1 "GND")
			(pinfunction "A")
			(pintype "passive")
		)
	)
	(footprint "antmicro-footprints:R_0402_1005Metric"
		(layer "F.Cu")
		(at 61.6 106)
		(descr "Resistor SMD 0402")
		(tags "resistor SMD 0402")
		(property "Reference" "R77"
			(at 0.75 0.45 0)
			(layer "F.SilkS")
			(effects
				(font
					(size 0.7 0.7)
					(thickness 0.15)
				)
				(justify left bottom)
			)
		)
		(property "Value" "R_10k_0402"
			(at 0 1.4 0)
			(layer "F.Fab")
			(effects
				(font
					(size 0.7 0.7)
					(thickness 0.15)
				)
				(justify left bottom)
			)
		)
		(property "Footprint" "antmicro-footprints:R_0402_1005Metric"
			(at 0 0 0)
			(layer "F.Fab")
			(hide yes)
			(effects
				(font
					(size 1.27 1.27)
					(thickness 0.15)
				)
			)
		)
		(property "Datasheet" "https://www.bourns.com/docs/product-datasheets/cr.pdf"
			(at 0 0 0)
			(layer "F.Fab")
			(hide yes)
			(effects
				(font
					(size 1.27 1.27)
					(thickness 0.15)
				)
			)
		)
		(property "Author" "Antmicro"
			(at 0 0 0)
			(layer "F.Fab")
			(hide yes)
			(effects
				(font
					(size 1 1)
					(thickness 0.15)
				)
			)
		)
		(property "License" "Apache-2.0"
			(at 0 0 0)
			(layer "F.Fab")
			(hide yes)
			(effects
				(font
					(size 1 1)
					(thickness 0.15)
				)
			)
		)
		(property "MPN" "CR0402-FX-1002GLF"
			(at 0 0 0)
			(layer "F.Fab")
			(hide yes)
			(effects
				(font
					(size 1 1)
					(thickness 0.15)
				)
			)
		)
		(property "Manufacturer" "Bourns"
			(at 0 0 0)
			(layer "F.Fab")
			(hide yes)
			(effects
				(font
					(size 1 1)
					(thickness 0.15)
				)
			)
		)
		(property "Tolerance" "1%"
			(at 0 0 0)
			(layer "F.Fab")
			(hide yes)
			(effects
				(font
					(size 1 1)
					(thickness 0.15)
				)
			)
		)
		(property "Val" "10k"
			(at 0 0 0)
			(layer "F.Fab")
			(hide yes)
			(effects
				(font
					(size 1 1)
					(thickness 0.15)
				)
			)
		)
		(sheetname "USB Debug, DP")
		(sheetfile "usb.kicad_sch")
		(attr smd)
		(fp_rect
			(start -0.925 -0.47)
			(end 0.925 0.47)
			(stroke
				(width 0.05)
				(type default)
			)
			(fill none)
			(layer "F.CrtYd")
		)
		(fp_rect
			(start -0.5 -0.25)
			(end 0.5 0.25)
			(stroke
				(width 0.15)
				(type solid)
			)
			(fill none)
			(layer "F.Fab")
		)
		(fp_text user "${REFERENCE}"
			(at -0.95 3.168 0)
			(layer "F.Fab")
			(hide yes)
			(effects
				(font
					(size 0.7 0.7)
					(thickness 0.15)
				)
				(justify left bottom)
			)
		)
		(fp_text user "Author: Antmicro"
			(at -0.95 4.169 0)
			(layer "F.Fab")
			(hide yes)
			(effects
				(font
					(size 0.7 0.7)
					(thickness 0.15)
				)
				(justify left bottom)
			)
		)
		(fp_text user "License: Apache-2.0"
			(at -0.95 5.169 0)
			(layer "F.Fab")
			(hide yes)
			(effects
				(font
					(size 0.7 0.7)
					(thickness 0.15)
				)
				(justify left bottom)
			)
		)
		(pad "1" smd roundrect
			(at -0.48 0)
			(size 0.59 0.64)
			(layers "F.Cu" "F.Paste" "F.Mask")
			(roundrect_rratio 0.25)
			(net 1 "GND")
			(pintype "passive")
		)
		(pad "2" smd roundrect
			(at 0.48 0)
			(size 0.59 0.64)
			(layers "F.Cu" "F.Paste" "F.Mask")
			(roundrect_rratio 0.25)
			(net 657 "Net-(U9-EN)")
			(pintype "passive")
		)
	)
	(footprint "antmicro-footprints:XDFN-2_1x0.60mm"
		(layer "F.Cu")
		(at 137.8 82.8 90)
		(property "Reference" "D47"
			(at -0.3 0.4 0)
			(layer "F.SilkS")
			(effects
				(font
					(size 0.7 0.7)
					(thickness 0.15)
				)
				(justify left bottom)
			)
		)
		(property "Value" "TPD1E0B04_XDFN-2"
			(at 0 1.5 90)
			(layer "F.Fab")
			(effects
				(font
					(size 0.7 0.7)
					(thickness 0.15)
				)
				(justify left bottom)
			)
		)
		(property "Footprint" "antmicro-footprints:XDFN-2_1x0.60mm"
			(at 0 0 90)
			(layer "F.Fab")
			(hide yes)
			(effects
				(font
					(size 1.27 1.27)
					(thickness 0.15)
				)
			)
		)
		(property "Datasheet" "https://www.ti.com/general/docs/suppproductinfo.tsp?distId=26&gotoUrl=https://www.ti.com/lit/gpn/tpd1e0b04"
			(at 0 0 90)
			(layer "F.Fab")
			(hide yes)
			(effects
				(font
					(size 1.27 1.27)
					(thickness 0.15)
				)
			)
		)
		(property "MPN" "TPD1E0B04DPYR"
			(at 220.6 -55 0)
			(layer "F.Fab")
			(hide yes)
			(effects
				(font
					(size 1 1)
					(thickness 0.15)
				)
			)
		)
		(property "Manufacturer" "Texas Instruments"
			(at 220.6 -55 0)
			(layer "F.Fab")
			(hide yes)
			(effects
				(font
					(size 1 1)
					(thickness 0.15)
				)
			)
		)
		(property "Author" "Antmicro"
			(at 220.6 -55 0)
			(layer "F.Fab")
			(hide yes)
			(effects
				(font
					(size 1 1)
					(thickness 0.15)
				)
			)
		)
		(property "License" "Apache-2.0"
			(at 220.6 -55 0)
			(layer "F.Fab")
			(hide yes)
			(effects
				(font
					(size 1 1)
					(thickness 0.15)
				)
			)
		)
		(sheetname "Peripherals")
		(sheetfile "peripherals.kicad_sch")
		(attr smd)
		(fp_rect
			(start -0.725 -0.475)
			(end 0.725 0.475)
			(stroke
				(width 0.05)
				(type solid)
			)
			(fill none)
			(layer "F.CrtYd")
		)
		(fp_rect
			(start -0.55 -0.35)
			(end 0.55 0.35)
			(stroke
				(width 0.15)
				(type solid)
			)
			(fill none)
			(layer "F.Fab")
		)
		(fp_text user "Author: Antmicro"
			(at -0.8 4.4 90)
			(layer "F.Fab")
			(hide yes)
			(effects
				(font
					(size 0.7 0.7)
					(thickness 0.15)
				)
				(justify left bottom)
			)
		)
		(fp_text user "${REFERENCE}"
			(at -0.8 3.2 90)
			(layer "F.Fab")
			(hide yes)
			(effects
				(font
					(size 0.7 0.7)
					(thickness 0.15)
				)
				(justify left bottom)
			)
		)
		(fp_text user "License: Apache-2.0"
			(at -0.8 5.6 90)
			(layer "F.Fab")
			(hide yes)
			(effects
				(font
					(size 0.7 0.7)
					(thickness 0.15)
				)
				(justify left bottom)
			)
		)
		(pad "1" smd roundrect
			(at -0.351 0 90)
			(size 0.3 0.5)
			(layers "F.Cu" "F.Paste" "F.Mask")
			(roundrect_rratio 0.25)
			(net 415 "/Peripherals/PCIE2_TX1_CONN_N")
			(pinfunction "C")
			(pintype "passive")
		)
		(pad "2" smd roundrect
			(at 0.349 0 90)
			(size 0.3 0.5)
			(layers "F.Cu" "F.Paste" "F.Mask")
			(roundrect_rratio 0.25)
			(net 1 "GND")
			(pinfunction "A")
			(pintype "passive")
		)
	)
	(footprint "antmicro-footprints:C_0603_1608Metric_EIA"
		(layer "F.Cu")
		(at 59.36 94.63 90)
		(descr "Capacitor SMD 0603, IPC-7351 Density Level A")
		(tags "Capacitor 0603")
		(property "Reference" "C153"
			(at -2.32 28.119999 90)
			(layer "F.SilkS")
			(effects
				(font
					(size 0.7 0.7)
					(thickness 0.15)
				)
				(justify left bottom)
			)
		)
		(property "Value" "C_22u_16V_0603"
			(at -1.42757 1.770288 90)
			(layer "F.Fab")
			(effects
				(font
					(size 0.7 0.7)
					(thickness 0.15)
				)
				(justify left bottom)
			)
		)
		(property "Footprint" "antmicro-footprints:C_0603_1608Metric_EIA"
			(at 0 0 90)
			(layer "F.Fab")
			(hide yes)
			(effects
				(font
					(size 1.27 1.27)
					(thickness 0.15)
				)
			)
		)
		(property "Datasheet" "https://product.samsungsem.com/mlcc/CL10A226MO7JZN.do"
			(at 0 0 90)
			(layer "F.Fab")
			(hide yes)
			(effects
				(font
					(size 1.27 1.27)
					(thickness 0.15)
				)
			)
		)
		(property "Description" "SMD Multilayer Ceramic Capacitor"
			(at 0 0 90)
			(layer "F.Fab")
			(hide yes)
			(effects
				(font
					(size 1.27 1.27)
					(thickness 0.15)
				)
			)
		)
		(property "Manufacturer" "Samsung Electro-Mechanics"
			(at 0 0 90)
			(unlocked yes)
			(layer "F.Fab")
			(hide yes)
			(effects
				(font
					(size 1 1)
					(thickness 0.15)
				)
			)
		)
		(property "MPN" "CL10A226MO7JZNC"
			(at 0 0 90)
			(unlocked yes)
			(layer "F.Fab")
			(hide yes)
			(effects
				(font
					(size 1 1)
					(thickness 0.15)
				)
			)
		)
		(property "Val" "22u"
			(at 0 0 90)
			(unlocked yes)
			(layer "F.Fab")
			(hide yes)
			(effects
				(font
					(size 1 1)
					(thickness 0.15)
				)
			)
		)
		(property "License" "Apache-2.0"
			(at 0 0 90)
			(unlocked yes)
			(layer "F.Fab")
			(hide yes)
			(effects
				(font
					(size 1 1)
					(thickness 0.15)
				)
			)
		)
		(property "Author" "Antmicro"
			(at 0 0 90)
			(unlocked yes)
			(layer "F.Fab")
			(hide yes)
			(effects
				(font
					(size 1 1)
					(thickness 0.15)
				)
			)
		)
		(property "Voltage" "16V"
			(at 0 0 90)
			(unlocked yes)
			(layer "F.Fab")
			(hide yes)
			(effects
				(font
					(size 1 1)
					(thickness 0.15)
				)
			)
		)
		(property "Dielectric" ""
			(at 0 0 90)
			(unlocked yes)
			(layer "F.Fab")
			(hide yes)
			(effects
				(font
					(size 1 1)
					(thickness 0.15)
				)
			)
		)
		(sheetname "Supply")
		(sheetfile "supply.kicad_sch")
		(attr smd)
		(fp_line
			(start -0.15 -0.55)
			(end 0.15 -0.55)
			(stroke
				(width 0.15)
				(type solid)
			)
			(layer "F.SilkS")
		)
		(fp_line
			(start -0.15 0.55)
			(end 0.15 0.55)
			(stroke
				(width 0.15)
				(type solid)
			)
			(layer "F.SilkS")
		)
		(fp_rect
			(start -1.25 -0.65)
			(end 1.25 0.65)
			(stroke
				(width 0.05)
				(type solid)
			)
			(fill none)
			(layer "F.CrtYd")
		)
		(fp_rect
			(start -0.8 -0.45)
			(end 0.8 0.45)
			(stroke
				(width 0.15)
				(type solid)
			)
			(fill none)
			(layer "F.Fab")
		)
		(fp_text user "License: Apache-2.0"
			(at -1.682 5.895 90)
			(layer "F.Fab")
			(hide yes)
			(effects
				(font
					(size 0.7 0.7)
					(thickness 0.15)
				)
				(justify left bottom)
			)
		)
		(fp_text user "${REFERENCE}"
			(at -1.682 3.895 90)
			(layer "F.Fab")
			(hide yes)
			(effects
				(font
					(size 0.7 0.7)
					(thickness 0.15)
				)
				(justify left bottom)
			)
		)
		(fp_text user "Author: Antmicro"
			(at -1.682 4.894 90)
			(layer "F.Fab")
			(hide yes)
			(effects
				(font
					(size 0.7 0.7)
					(thickness 0.15)
				)
				(justify left bottom)
			)
		)
		(pad "1" smd roundrect
			(at -0.7 0 90)
			(size 0.8 1.1)
			(layers "F.Cu" "F.Paste" "F.Mask")
			(roundrect_rratio 0.2)
			(net 1 "GND")
			(pintype "passive")
		)
		(pad "2" smd roundrect
			(at 0.7 0 90)
			(size 0.8 1.1)
			(layers "F.Cu" "F.Paste" "F.Mask")
			(roundrect_rratio 0.2)
			(net 761 "/Supply/5V_OUT")
			(pintype "passive")
		)
	)
)
